# BASEBOARD_FAB2 (Tioga Pass) — schematic netlist excerpt (pin names and nets, part order shuffled) for the footprints in the layout excerpt that follows; sources: Cadence DE-HDL packaged netlist, KiCad conversion of Wiwynn_Tioga_Pass_MB.brd

J6M1  SCONN288_H44441003  SCONN  pkg PIP  page 50
  \12v\(1)  = P12V_NVDIMM_DEF
  VSS(93)  = GND
  DQ(4)  = M_D_DQ<4>
  VSS(92)  = GND
  DQ(0)  = M_D_DQ<0>
  VSS(91)  = GND
  DQS9P  = M_D_DQS_DP<9>
  DQS9N  = M_D_DQS_DN<9>
  VSS(90)  = GND
  DQ(6)  = M_D_DQ<6>
  VSS(89)  = GND
  DQ(2)  = M_D_DQ<2>
  VSS(88)  = GND
  DQ(12)  = M_D_DQ<12>
  VSS(87)  = GND
  DQ(8)  = M_D_DQ<8>
  VSS(86)  = GND
  DQS10P  = M_D_DQS_DP<10>
  DQS10N  = M_D_DQS_DN<10>
  VSS(85)  = GND
  DQ(14)  = M_D_DQ<14>
  VSS(84)  = GND
  DQ(10)  = M_D_DQ<10>
  VSS(83)  = GND
  DQ(20)  = M_D_DQ<20>
  VSS(82)  = GND
  DQ(16)  = M_D_DQ<16>
  VSS(81)  = GND
  DQS11P  = M_D_DQS_DP<11>
  DQS11N  = M_D_DQS_DN<11>
  VSS(80)  = GND
  DQ(22)  = M_D_DQ<22>
  VSS(79)  = GND
  DQ(18)  = M_D_DQ<18>
  VSS(78)  = GND
  DQ(28)  = M_D_DQ<28>
  VSS(77)  = GND
  DQ(24)  = M_D_DQ<24>
  VSS(76)  = GND
  DQS12P  = M_D_DQS_DP<12>
  DQS12N  = M_D_DQS_DN<12>
  VSS(75)  = GND
  DQ(30)  = M_D_DQ<30>
  VSS(74)  = GND
  DQ(26)  = M_D_DQ<26>
  VSS(73)  = GND
  CB(4)  = M_D_ECC<4>
  VSS(72)  = GND
  CB(0)  = M_D_ECC<0>
  VSS(71)  = GND
  DQS17P  = M_D_DQS_DP<17>
  DQS17N  = M_D_DQS_DN<17>
  VSS(70)  = GND
  CB(6)  = M_D_ECC<6>
  VSS(69)  = GND
  CB(2)  = M_D_ECC<2>
  VSS(68)  = GND
  RESET_N  = M_DEF_RST_N
  VDD(25)  = PVDDQ_DEF
  CKE(0)  = M_D_CKE<2>
  VDD(24)  = PVDDQ_DEF
  ACT_N  = M_D_ACT_N
  BG(0)  = M_D_BG<0>
  VDD(23)  = PVDDQ_DEF
  A12  = M_D_MA<12>
  A9  = M_D_MA<9>
  VDD(22)  = PVDDQ_DEF
  A8  = M_D_MA<8>
  A6  = M_D_MA<6>
  VDD(21)  = PVDDQ_DEF
  A3  = M_D_MA<3>
  A1  = M_D_MA<1>
  VDD(20)  = PVDDQ_DEF
  CK0P  = M_D_CLK_DP<2>
  CK0N  = M_D_CLK_DN<2>
  VDD(19)  = PVDDQ_DEF
  VTT(1)  = PVTT_DEF
  EVENT_N  = FM_DIMM_EVENT_COD_N
  A0  = M_D_MA<0>
  VDD(18)  = PVDDQ_DEF
  BA(0)  = M_D_BA<0>
  A16_RAS_N  = M_D_MA<16>
  VDD(17)  = PVDDQ_DEF
  S0_N  = M_D_CS_N<4>
  VDD(16)  = PVDDQ_DEF
  A15_CAS_N  = M_D_MA<15>
  ODT(0)  = M_D_ODT<2>
  VDD(15)  = PVDDQ_DEF
  S1_N  = M_D_CS_N<5>
  VDD(14)  = PVDDQ_DEF
  ODT(1)  = M_D_ODT<3>
  VDD(13)  = PVDDQ_DEF
  S2_N_C(0)  = M_D_CS_N<6>
  VSS(67)  = GND
  DQ(36)  = M_D_DQ<36>
  VSS(66)  = GND
  DQ(32)  = M_D_DQ<32>
  VSS(65)  = GND
  DQS13P  = M_D_DQS_DP<13>
  DQS13N  = M_D_DQS_DN<13>
  VSS(64)  = GND
  DQ(38)  = M_D_DQ<38>
  VSS(63)  = GND
  DQ(34)  = M_D_DQ<34>
  VSS(62)  = GND
  DQ(44)  = M_D_DQ<44>
  VSS(61)  = GND
  DQ(40)  = M_D_DQ<40>
  VSS(60)  = GND
  DQS14P  = M_D_DQS_DP<14>
  DQS14N  = M_D_DQS_DN<14>
  VSS(59)  = GND
  DQ(46)  = M_D_DQ<46>
  VSS(58)  = GND
  DQ(42)  = M_D_DQ<42>
  VSS(57)  = GND
  DQ(52)  = M_D_DQ<52>
  VSS(56)  = GND
  DQ(48)  = M_D_DQ<48>
  VSS(55)  = GND
  DQS15P  = M_D_DQS_DP<15>
  DQS15N  = M_D_DQS_DN<15>
  VSS(54)  = GND
  DQ(54)  = M_D_DQ<54>
  VSS(53)  = GND
  DQ(50)  = M_D_DQ<50>
  VSS(52)  = GND
  DQ(60)  = M_D_DQ<60>
  VSS(51)  = GND
  DQ(56)  = M_D_DQ<56>
  VSS(50)  = GND
  DQS16P  = M_D_DQS_DP<16>
  DQS16N  = M_D_DQS_DN<16>
  VSS(49)  = GND
  DQ(62)  = M_D_DQ<62>
  VSS(48)  = GND
  DQ(58)  = M_D_DQ<58>
  VSS(47)  = GND
  SA(0)  = PVPP_DEF
  SA(1)  = GND
  SCL  = SMB_DDR_DEF_VPP_SCL
  VPP(4)  = PVPP_DEF
  VPP(3)  = PVPP_DEF
  RFU(2)  = TP_CH_D_DIMM_D1_RFU_2
  \12v\(0)  = P12V_NVDIMM_DEF
  VREFCA  = M_D_VREF
  VSS(46)  = GND
  DQ(5)  = M_D_DQ<5>
  VSS(45)  = GND
  DQ(1)  = M_D_DQ<1>
  VSS(44)  = GND
  DQS0N  = M_D_DQS_DN<0>
  DQS0P  = M_D_DQS_DP<0>
  VSS(43)  = GND
  DQ(7)  = M_D_DQ<7>
  VSS(42)  = GND
  DQ(3)  = M_D_DQ<3>
  VSS(41)  = GND
  DQ(13)  = M_D_DQ<13>
  VSS(40)  = GND
  DQ(9)  = M_D_DQ<9>
  VSS(39)  = GND
  DQS1N  = M_D_DQS_DN<1>
  DQS1P  = M_D_DQS_DP<1>
  VSS(38)  = GND
  DQ(15)  = M_D_DQ<15>
  VSS(37)  = GND
  DQ(11)  = M_D_DQ<11>
  VSS(36)  = GND
  DQ(21)  = M_D_DQ<21>
  VSS(35)  = GND
  DQ(17)  = M_D_DQ<17>
  VSS(34)  = GND
  DQS2N  = M_D_DQS_DN<2>
  DQS2P  = M_D_DQS_DP<2>
  VSS(33)  = GND
  DQ(23)  = M_D_DQ<23>
  VSS(32)  = GND
  DQ(19)  = M_D_DQ<19>
  VSS(31)  = GND
  DQ(29)  = M_D_DQ<29>
  VSS(30)  = GND
  DQ(25)  = M_D_DQ<25>
  VSS(29)  = GND
  DQS3N  = M_D_DQS_DN<3>
  DQS3P  = M_D_DQS_DP<3>
  VSS(28)  = GND
  DQ(31)  = M_D_DQ<31>
  VSS(27)  = GND
  DQ(27)  = M_D_DQ<27>
  VSS(26)  = GND
  CB(5)  = M_D_ECC<5>
  VSS(25)  = GND
  CB(1)  = M_D_ECC<1>
  VSS(24)  = GND
  DQS8N  = M_D_DQS_DN<8>
  DQS8P  = M_D_DQS_DP<8>
  VSS(23)  = GND
  CB(7)  = M_D_ECC<7>
  VSS(22)  = GND
  CB(3)  = M_D_ECC<3>
  VSS(21)  = GND
  CKE(1)  = M_D_CKE<3>
  VDD(12)  = PVDDQ_DEF
  RFU(0)  = TP_CH_D_DIMM_D1_RFU_0
  VDD(11)  = PVDDQ_DEF
  BG(1)  = M_D_BG<1>
  ALERT_N  = M_D_ALERT_N
  VDD(10)  = PVDDQ_DEF
  A11  = M_D_MA<11>
  A7  = M_D_MA<7>
  VDD(9)  = PVDDQ_DEF
  A5  = M_D_MA<5>
  A4  = M_D_MA<4>
  VDD(8)  = PVDDQ_DEF
  A2  = M_D_MA<2>
  VDD(7)  = PVDDQ_DEF
  CK1P  = M_D_CLK_DP<3>
  CK1N  = M_D_CLK_DN<3>
  VDD(6)  = PVDDQ_DEF
  VTT(0)  = PVTT_DEF
  PAR  = M_D_PAR
  VDD(5)  = PVDDQ_DEF
  BA(1)  = M_D_BA<1>
  A10  = M_D_MA<10>
  VDD(4)  = PVDDQ_DEF
  RFU(1)  = TP_CH_D_DIMM_D1_RFU_1
  A14_WE_N  = M_D_MA<14>
  VDD(3)  = PVDDQ_DEF
  SAVE_N_NC  = FM_ADR_COMPLETE_DEF_N
  VDD(2)  = PVDDQ_DEF
  A13  = M_D_MA<13>
  VDD(1)  = PVDDQ_DEF
  A17  = M_D_MA<17>
  C(2)  = M_D_C<2>
  VDD(0)  = PVDDQ_DEF
  S3_N_C(1)  = M_D_CS_N<7>
  SA(2)  = GND
  VSS(20)  = GND
  DQ(37)  = M_D_DQ<37>
  VSS(19)  = GND
  DQ(33)  = M_D_DQ<33>
  VSS(18)  = GND
  DQS4N  = M_D_DQS_DN<4>
  DQS4P  = M_D_DQS_DP<4>
  VSS(17)  = GND
  DQ(39)  = M_D_DQ<39>
  VSS(16)  = GND
  DQ(35)  = M_D_DQ<35>
  VSS(15)  = GND
  DQ(45)  = M_D_DQ<45>
  VSS(14)  = GND
  DQ(41)  = M_D_DQ<41>
  VSS(13)  = GND
  DQS5N  = M_D_DQS_DN<5>
  DQS5P  = M_D_DQS_DP<5>
  VSS(12)  = GND
  DQ(47)  = M_D_DQ<47>
  VSS(11)  = GND
  DQ(43)  = M_D_DQ<43>
  VSS(10)  = GND
  DQ(53)  = M_D_DQ<53>
  VSS(9)  = GND
  DQ(49)  = M_D_DQ<49>
  VSS(8)  = GND
  DQS6N  = M_D_DQS_DN<6>
  DQS6P  = M_D_DQS_DP<6>
  VSS(7)  = GND
  DQ(55)  = M_D_DQ<55>
  VSS(6)  = GND
  DQ(51)  = M_D_DQ<51>
  VSS(5)  = GND
  DQ(61)  = M_D_DQ<61>
  VSS(4)  = GND
  DQ(57)  = M_D_DQ<57>
  VSS(3)  = GND
  DQS7N  = M_D_DQS_DN<7>
  DQS7P  = M_D_DQS_DP<7>
  VSS(2)  = GND
  DQ(63)  = M_D_DQ<63>
  VSS(1)  = GND
  DQ(59)  = M_D_DQ<59>
  VSS(0)  = GND
  VDDSPD  = PVPP_DEF
  SDA  = SMB_DDR_DEF_VPP_SDA
  VPP(1)  = PVPP_DEF
  VPP(0)  = PVPP_DEF
  VPP(2)  = PVPP_DEF

(kicad_pcb
	(version 20260206)
	(generator "pcbnew")
	(generator_version "10.0")
	(general
		(thickness 1.6)
		(legacy_teardrops no)
	)
	(paper "A4")
	(title_block
		(title "Wiwynn_Tioga_Pass_MB.brd")
		(comment 1 "Tioga Pass / footprint 3254 of 4770 (J6M1), pads 202-249 of 291")
	)
	(layers
		(0 "F.Cu" signal "TOP")
		(4 "In1.Cu" signal "L2GND")
		(6 "In2.Cu" signal "L3")
		(8 "In3.Cu" signal "L4GND")
		(10 "In4.Cu" signal "L5")
		(12 "In5.Cu" signal "L6GND")
		(14 "In6.Cu" signal "L7VCC")
		(16 "In7.Cu" signal "L8VCC")
		(18 "In8.Cu" signal "L9GND")
		(20 "In9.Cu" signal "L10")
		(22 "In10.Cu" signal "L11GND")
		(24 "In11.Cu" signal "L12")
		(26 "In12.Cu" signal "L13GND")
		(2 "B.Cu" signal "BOTTOM")
		(9 "F.Adhes" user "F.Adhesive")
		(11 "B.Adhes" user "B.Adhesive")
		(13 "F.Paste" user "Package Geometry/Pastemask Top")
		(15 "B.Paste" user "Package Geometry/Pastemask Bottom")
		(5 "F.SilkS" user "Ref Des/Silkscreen Top")
		(7 "B.SilkS" user "Ref Des/Silkscreen Bottom")
		(1 "F.Mask" user "Board Geometry/Soldermask Top")
		(3 "B.Mask" user "Board Geometry/Soldermask Bottom")
		(17 "Dwgs.User" user "User.Drawings")
		(19 "Cmts.User" user "User.Comments")
		(21 "Eco1.User" user "User.Eco1")
		(23 "Eco2.User" user "User.Eco2")
		(25 "Edge.Cuts" user "Board Geometry/Outline")
		(27 "Margin" user)
		(31 "F.CrtYd" user "Package Geometry/Place Bound Top")
		(29 "B.CrtYd" user "Package Geometry/Place Bound Bottom")
		(35 "F.Fab" user "Ref Des/Assembly Top")
		(33 "B.Fab" user "Ref Des/Assembly Bottom")
	)
	(footprint ""
		(layer "B.Cu")
		(at 194.700398 -132.876036 90)
		(property "Reference" "J6M1"
			(at 2.352548 37.96411 0)
			(unlocked yes)
			(layer "B.SilkS")
			(effects
				(font
					(size 0.7874 0.5842)
					(thickness 0.1524)
				)
				(justify left mirror)
			)
		)
		(property "Value" ""
			(at 0 0 90)
			(layer "B.Fab")
			(effects
				(font
					(size 1.27 1.27)
				)
				(justify mirror)
			)
		)
		(duplicate_pad_numbers_are_jumpers no)
		(pad "199" smd rect
			(at -4.59994 45.900086 270)
			(size 1.8034 0.508)
			(layers "B.Cu" "B.Mask" "B.Paste")
			(net "M_D_ECC<7>")
		)
		(pad "200" smd rect
			(at -4.59994 46.74997 270)
			(size 1.8034 0.508)
			(layers "B.Cu" "B.Mask" "B.Paste")
			(net "GND")
		)
		(pad "201" smd rect
			(at -4.59994 47.600108 270)
			(size 1.8034 0.508)
			(layers "B.Cu" "B.Mask" "B.Paste")
			(net "M_D_ECC<3>")
		)
		(pad "202" smd rect
			(at -4.59994 48.449992 270)
			(size 1.8034 0.508)
			(layers "B.Cu" "B.Mask" "B.Paste")
			(net "GND")
		)
		(pad "203" smd rect
			(at -4.59994 49.299876 270)
			(size 1.8034 0.508)
			(layers "B.Cu" "B.Mask" "B.Paste")
			(net "M_D_CKE<3>")
		)
		(pad "204" smd rect
			(at -4.59994 50.150014 270)
			(size 1.8034 0.508)
			(layers "B.Cu" "B.Mask" "B.Paste")
			(net "PVDDQ_DEF")
		)
		(pad "205" smd rect
			(at -4.59994 50.999898 270)
			(size 1.8034 0.508)
			(layers "B.Cu" "B.Mask" "B.Paste")
			(net "TP_CH_D_DIMM_D1_RFU_0")
		)
		(pad "206" smd rect
			(at -4.59994 51.850036 270)
			(size 1.8034 0.508)
			(layers "B.Cu" "B.Mask" "B.Paste")
			(net "PVDDQ_DEF")
		)
		(pad "207" smd rect
			(at -4.59994 52.69992 270)
			(size 1.8034 0.508)
			(layers "B.Cu" "B.Mask" "B.Paste")
			(net "M_D_BG<1>")
		)
		(pad "208" smd rect
			(at -4.59994 53.550058 270)
			(size 1.8034 0.508)
			(layers "B.Cu" "B.Mask" "B.Paste")
			(net "M_D_ALERT_N")
		)
		(pad "209" smd rect
			(at -4.59994 54.399942 270)
			(size 1.8034 0.508)
			(layers "B.Cu" "B.Mask" "B.Paste")
			(net "PVDDQ_DEF")
		)
		(pad "210" smd rect
			(at -4.59994 55.25008 270)
			(size 1.8034 0.508)
			(layers "B.Cu" "B.Mask" "B.Paste")
			(net "M_D_MA<11>")
		)
		(pad "211" smd rect
			(at -4.59994 56.099964 270)
			(size 1.8034 0.508)
			(layers "B.Cu" "B.Mask" "B.Paste")
			(net "M_D_MA<7>")
		)
		(pad "212" smd rect
			(at -4.59994 56.950102 270)
			(size 1.8034 0.508)
			(layers "B.Cu" "B.Mask" "B.Paste")
			(net "PVDDQ_DEF")
		)
		(pad "213" smd rect
			(at -4.59994 57.799986 270)
			(size 1.8034 0.508)
			(layers "B.Cu" "B.Mask" "B.Paste")
			(net "M_D_MA<5>")
		)
		(pad "214" smd rect
			(at -4.59994 58.650124 270)
			(size 1.8034 0.508)
			(layers "B.Cu" "B.Mask" "B.Paste")
			(net "M_D_MA<4>")
		)
		(pad "215" smd rect
			(at -4.59994 59.500008 270)
			(size 1.8034 0.508)
			(layers "B.Cu" "B.Mask" "B.Paste")
			(net "PVDDQ_DEF")
		)
		(pad "216" smd rect
			(at -4.59994 60.349892 270)
			(size 1.8034 0.508)
			(layers "B.Cu" "B.Mask" "B.Paste")
			(net "M_D_MA<2>")
		)
		(pad "217" smd rect
			(at -4.59994 61.20003 270)
			(size 1.8034 0.508)
			(layers "B.Cu" "B.Mask" "B.Paste")
			(net "PVDDQ_DEF")
		)
		(pad "218" smd rect
			(at -4.59994 62.049914 270)
			(size 1.8034 0.508)
			(layers "B.Cu" "B.Mask" "B.Paste")
			(net "M_D_CLK_DP<3>")
		)
		(pad "219" smd rect
			(at -4.59994 62.900052 270)
			(size 1.8034 0.508)
			(layers "B.Cu" "B.Mask" "B.Paste")
			(net "M_D_CLK_DN<3>")
		)
		(pad "220" smd rect
			(at -4.59994 63.749936 270)
			(size 1.8034 0.508)
			(layers "B.Cu" "B.Mask" "B.Paste")
			(net "PVDDQ_DEF")
		)
		(pad "221" smd rect
			(at -4.59994 64.600074 270)
			(size 1.8034 0.508)
			(layers "B.Cu" "B.Mask" "B.Paste")
			(net "PVTT_DEF")
		)
		(pad "222" smd rect
			(at -4.59994 70.550024 270)
			(size 1.8034 0.508)
			(layers "B.Cu" "B.Mask" "B.Paste")
			(net "M_D_PAR")
		)
		(pad "223" smd rect
			(at -4.59994 71.399908 270)
			(size 1.8034 0.508)
			(layers "B.Cu" "B.Mask" "B.Paste")
			(net "PVDDQ_DEF")
		)
		(pad "224" smd rect
			(at -4.59994 72.250046 270)
			(size 1.8034 0.508)
			(layers "B.Cu" "B.Mask" "B.Paste")
			(net "M_D_BA<1>")
		)
		(pad "225" smd rect
			(at -4.59994 73.09993 270)
			(size 1.8034 0.508)
			(layers "B.Cu" "B.Mask" "B.Paste")
			(net "M_D_MA<10>")
		)
		(pad "226" smd rect
			(at -4.59994 73.950068 270)
			(size 1.8034 0.508)
			(layers "B.Cu" "B.Mask" "B.Paste")
			(net "PVDDQ_DEF")
		)
		(pad "227" smd rect
			(at -4.59994 74.799952 270)
			(size 1.8034 0.508)
			(layers "B.Cu" "B.Mask" "B.Paste")
			(net "TP_CH_D_DIMM_D1_RFU_1")
		)
		(pad "228" smd rect
			(at -4.59994 75.65009 270)
			(size 1.8034 0.508)
			(layers "B.Cu" "B.Mask" "B.Paste")
			(net "M_D_MA<14>")
		)
		(pad "229" smd rect
			(at -4.59994 76.499974 270)
			(size 1.8034 0.508)
			(layers "B.Cu" "B.Mask" "B.Paste")
			(net "PVDDQ_DEF")
		)
		(pad "230" smd rect
			(at -4.59994 77.350112 270)
			(size 1.8034 0.508)
			(layers "B.Cu" "B.Mask" "B.Paste")
			(net "FM_ADR_COMPLETE_DEF_N")
		)
		(pad "231" smd rect
			(at -4.59994 78.199996 270)
			(size 1.8034 0.508)
			(layers "B.Cu" "B.Mask" "B.Paste")
			(net "PVDDQ_DEF")
		)
		(pad "232" smd rect
			(at -4.59994 79.04988 270)
			(size 1.8034 0.508)
			(layers "B.Cu" "B.Mask" "B.Paste")
			(net "M_D_MA<13>")
		)
		(pad "233" smd rect
			(at -4.59994 79.900018 270)
			(size 1.8034 0.508)
			(layers "B.Cu" "B.Mask" "B.Paste")
			(net "PVDDQ_DEF")
		)
		(pad "234" smd rect
			(at -4.59994 80.749902 270)
			(size 1.8034 0.508)
			(layers "B.Cu" "B.Mask" "B.Paste")
			(net "M_D_MA<17>")
		)
		(pad "235" smd rect
			(at -4.59994 81.60004 270)
			(size 1.8034 0.508)
			(layers "B.Cu" "B.Mask" "B.Paste")
			(net "M_D_C<2>")
		)
		(pad "236" smd rect
			(at -4.59994 82.449924 270)
			(size 1.8034 0.508)
			(layers "B.Cu" "B.Mask" "B.Paste")
			(net "PVDDQ_DEF")
		)
		(pad "237" smd rect
			(at -4.59994 83.300062 270)
			(size 1.8034 0.508)
			(layers "B.Cu" "B.Mask" "B.Paste")
			(net "M_D_CS_N<7>")
		)
		(pad "238" smd rect
			(at -4.59994 84.149946 270)
			(size 1.8034 0.508)
			(layers "B.Cu" "B.Mask" "B.Paste")
			(net "GND")
		)
		(pad "239" smd rect
			(at -4.59994 85.000084 270)
			(size 1.8034 0.508)
			(layers "B.Cu" "B.Mask" "B.Paste")
			(net "GND")
		)
		(pad "240" smd rect
			(at -4.59994 85.849968 270)
			(size 1.8034 0.508)
			(layers "B.Cu" "B.Mask" "B.Paste")
			(net "M_D_DQ<37>")
		)
		(pad "241" smd rect
			(at -4.59994 86.700106 270)
			(size 1.8034 0.508)
			(layers "B.Cu" "B.Mask" "B.Paste")
			(net "GND")
		)
		(pad "242" smd rect
			(at -4.59994 87.54999 270)
			(size 1.8034 0.508)
			(layers "B.Cu" "B.Mask" "B.Paste")
			(net "M_D_DQ<33>")
		)
		(pad "243" smd rect
			(at -4.59994 88.399874 270)
			(size 1.8034 0.508)
			(layers "B.Cu" "B.Mask" "B.Paste")
			(net "GND")
		)
		(pad "244" smd rect
			(at -4.59994 89.250012 270)
			(size 1.8034 0.508)
			(layers "B.Cu" "B.Mask" "B.Paste")
			(net "M_D_DQS_DN<4>")
		)
		(pad "245" smd rect
			(at -4.59994 90.099896 270)
			(size 1.8034 0.508)
			(layers "B.Cu" "B.Mask" "B.Paste")
			(net "M_D_DQS_DP<4>")
		)
		(pad "246" smd rect
			(at -4.59994 90.950034 270)
			(size 1.8034 0.508)
			(layers "B.Cu" "B.Mask" "B.Paste")
			(net "GND")
		)
	)
)
